# T6G (Grand Teton) — schematic netlist excerpt (pin names and nets, part order shuffled) for the footprints in the layout excerpt that follows; sources: Cadence DE-HDL packaged netlist, KiCad conversion of 04192023_DAF0TMB3IC0_F0TG_MB_C_brd_V02_OCP.brd

R71  Q_RES  33 5% CHIP  pkg 0402LF  page 84 : A = SCM_IRQ_R_N ; B = SCM_IRQ_N
C825  Q_CAP_DIFFBUS  DIFF BUS_0.22UF 6.3V 20% X6S  pkg C0201  page 65 : \1\ = P5E_CPU1_P0_TX_C_DP<6> ; \2\ = P5E_CPU1_P0_TX_DP<6>
L27  Q_INDUCTOR  BLM15PD121SN1D/1300MA IND  pkg SMLF  page 323 : \1\ = P1V8_CPU1_RT_1D ; \2\ = P1V8_CPU1_RT0_1A_1D

(kicad_pcb
	(version 20260206)
	(generator "pcbnew")
	(generator_version "10.0")
	(general
		(thickness 1.6)
		(legacy_teardrops no)
	)
	(paper "A4")
	(title_block
		(title "04192023_DAF0TMB3IC0_F0TG_MB_C_brd_V02_OCP.brd")
		(comment 1 "Grand Teton / footprints 534-536 of 8354")
	)
	(layers
		(0 "F.Cu" signal "TOP")
		(4 "In1.Cu" signal "GND")
		(6 "In2.Cu" signal "IN1")
		(8 "In3.Cu" signal "GND1")
		(10 "In4.Cu" signal "IN2")
		(12 "In5.Cu" signal "GND2")
		(14 "In6.Cu" signal "IN3")
		(16 "In7.Cu" signal "GND3")
		(18 "In8.Cu" signal "VCC")
		(20 "In9.Cu" signal "VCC1")
		(22 "In10.Cu" signal "GND4")
		(24 "In11.Cu" signal "IN4")
		(26 "In12.Cu" signal "GND5")
		(28 "In13.Cu" signal "IN5")
		(30 "In14.Cu" signal "GND6")
		(32 "In15.Cu" signal "IN6")
		(34 "In16.Cu" signal "GND7")
		(2 "B.Cu" signal "BOTTOM")
		(9 "F.Adhes" user "F.Adhesive")
		(11 "B.Adhes" user "B.Adhesive")
		(13 "F.Paste" user "Package Geometry/Pastemask Top")
		(15 "B.Paste" user "Package Geometry/Pastemask Bottom")
		(5 "F.SilkS" user "Ref Des/Silkscreen Top")
		(7 "B.SilkS" user "Ref Des/Silkscreen Bottom")
		(1 "F.Mask" user "Board Geometry/Soldermask Top")
		(3 "B.Mask" user "Board Geometry/Soldermask Bottom")
		(17 "Dwgs.User" user "User.Drawings")
		(19 "Cmts.User" user "User.Comments")
		(21 "Eco1.User" user "User.Eco1")
		(23 "Eco2.User" user "User.Eco2")
		(25 "Edge.Cuts" user "Board Geometry/Outline")
		(27 "Margin" user)
		(31 "F.CrtYd" user "Package Geometry/Place Bound Top")
		(29 "B.CrtYd" user "Package Geometry/Place Bound Bottom")
		(35 "F.Fab" user "Ref Des/Assembly Top")
		(33 "B.Fab" user "Ref Des/Assembly Bottom")
	)
	(footprint ""
		(layer "F.Cu")
		(at 151.13 -113.157 180)
		(property "Reference" "R71"
			(at 0 0 180)
			(layer "F.SilkS")
			(hide yes)
			(effects
				(font
					(size 1.27 1.27)
				)
			)
		)
		(property "Value" ""
			(at 0 0 180)
			(layer "F.Fab")
			(effects
				(font
					(size 1.27 1.27)
				)
			)
		)
		(duplicate_pad_numbers_are_jumpers no)
		(fp_line
			(start 0.7874 0.4064)
			(end -0.7874 0.4064)
			(stroke
				(width 0.1524)
				(type default)
			)
			(layer "F.SilkS")
		)
		(fp_line
			(start 0.7874 -0.4064)
			(end 0.7874 0.4064)
			(stroke
				(width 0.1524)
				(type default)
			)
			(layer "F.SilkS")
		)
		(fp_line
			(start -0.7874 0.4064)
			(end -0.7874 -0.4064)
			(stroke
				(width 0.1524)
				(type default)
			)
			(layer "F.SilkS")
		)
		(fp_line
			(start -0.7874 -0.4064)
			(end 0.7874 -0.4064)
			(stroke
				(width 0.1524)
				(type default)
			)
			(layer "F.SilkS")
		)
		(fp_line
			(start 0.67945 0.3048)
			(end 0.120396 0.3048)
			(stroke
				(width 0.1)
				(type default)
			)
			(layer "F.Fab")
		)
		(fp_line
			(start 0.67945 -0.3048)
			(end 0.67945 0.3048)
			(stroke
				(width 0.1)
				(type default)
			)
			(layer "F.Fab")
		)
		(fp_line
			(start 0.12065 -0.2794)
			(end 0.12065 -0.3048)
			(stroke
				(width 0.1)
				(type default)
			)
			(layer "F.Fab")
		)
		(fp_line
			(start 0.12065 -0.3048)
			(end 0.67945 -0.3048)
			(stroke
				(width 0.1)
				(type default)
			)
			(layer "F.Fab")
		)
		(fp_line
			(start 0.120396 0.3048)
			(end 0.120396 0.2794)
			(stroke
				(width 0.1)
				(type default)
			)
			(layer "F.Fab")
		)
		(fp_line
			(start 0.120396 0.2794)
			(end -0.12065 0.2794)
			(stroke
				(width 0.1)
				(type default)
			)
			(layer "F.Fab")
		)
		(fp_line
			(start -0.12065 0.3048)
			(end -0.67945 0.3048)
			(stroke
				(width 0.1)
				(type default)
			)
			(layer "F.Fab")
		)
		(fp_line
			(start -0.12065 0.2794)
			(end -0.12065 0.3048)
			(stroke
				(width 0.1)
				(type default)
			)
			(layer "F.Fab")
		)
		(fp_line
			(start -0.12065 -0.2794)
			(end 0.12065 -0.2794)
			(stroke
				(width 0.1)
				(type default)
			)
			(layer "F.Fab")
		)
		(fp_line
			(start -0.12065 -0.305054)
			(end -0.12065 -0.2794)
			(stroke
				(width 0.1)
				(type default)
			)
			(layer "F.Fab")
		)
		(fp_line
			(start -0.67945 0.3048)
			(end -0.67945 -0.305054)
			(stroke
				(width 0.1)
				(type default)
			)
			(layer "F.Fab")
		)
		(fp_line
			(start -0.67945 -0.305054)
			(end -0.12065 -0.305054)
			(stroke
				(width 0.1)
				(type default)
			)
			(layer "F.Fab")
		)
		(pad "1" smd circle
			(at -0.40005 0 180)
			(size 0 0)
			(layers "F.Cu" "F.Mask" "F.Paste")
			(net "SCM_IRQ_R_N")
		)
		(pad "2" smd circle
			(at 0.40005 0 180)
			(size 0 0)
			(layers "F.Cu" "F.Mask" "F.Paste")
			(net "SCM_IRQ_N")
		)
	)
	(footprint ""
		(layer "F.Cu")
		(at 70.662546 -385.09448 180)
		(property "Reference" "L27"
			(at 0 0 180)
			(layer "F.SilkS")
			(hide yes)
			(effects
				(font
					(size 1.27 1.27)
				)
			)
		)
		(property "Value" ""
			(at 0 0 180)
			(layer "F.Fab")
			(effects
				(font
					(size 1.27 1.27)
				)
			)
		)
		(duplicate_pad_numbers_are_jumpers no)
		(fp_line
			(start 0.762 0.381)
			(end -0.762 0.381)
			(stroke
				(width 0.1524)
				(type default)
			)
			(layer "F.SilkS")
		)
		(fp_line
			(start 0.762 -0.381)
			(end 0.762 0.381)
			(stroke
				(width 0.1524)
				(type default)
			)
			(layer "F.SilkS")
		)
		(fp_line
			(start -0.762 0.381)
			(end -0.762 -0.381)
			(stroke
				(width 0.1524)
				(type default)
			)
			(layer "F.SilkS")
		)
		(fp_line
			(start -0.762 -0.381)
			(end 0.762 -0.381)
			(stroke
				(width 0.1524)
				(type default)
			)
			(layer "F.SilkS")
		)
		(fp_line
			(start 0.680466 0.306324)
			(end 0.118364 0.306324)
			(stroke
				(width 0.1)
				(type default)
			)
			(layer "F.Fab")
		)
		(fp_line
			(start 0.680466 -0.306324)
			(end 0.680466 0.306324)
			(stroke
				(width 0.1)
				(type default)
			)
			(layer "F.Fab")
		)
		(fp_line
			(start 0.118872 -0.2794)
			(end 0.118872 -0.306324)
			(stroke
				(width 0.1)
				(type default)
			)
			(layer "F.Fab")
		)
		(fp_line
			(start 0.118872 -0.306324)
			(end 0.680466 -0.306324)
			(stroke
				(width 0.1)
				(type default)
			)
			(layer "F.Fab")
		)
		(fp_line
			(start 0.118364 0.306324)
			(end 0.118364 0.2794)
			(stroke
				(width 0.1)
				(type default)
			)
			(layer "F.Fab")
		)
		(fp_line
			(start 0.118364 0.2794)
			(end -0.119634 0.2794)
			(stroke
				(width 0.1)
				(type default)
			)
			(layer "F.Fab")
		)
		(fp_line
			(start -0.118364 -0.2794)
			(end 0.118872 -0.2794)
			(stroke
				(width 0.1)
				(type default)
			)
			(layer "F.Fab")
		)
		(fp_line
			(start -0.118364 -0.307086)
			(end -0.118364 -0.2794)
			(stroke
				(width 0.1)
				(type default)
			)
			(layer "F.Fab")
		)
		(fp_line
			(start -0.119634 0.30607)
			(end -0.681736 0.30607)
			(stroke
				(width 0.1)
				(type default)
			)
			(layer "F.Fab")
		)
		(fp_line
			(start -0.119634 0.2794)
			(end -0.119634 0.30607)
			(stroke
				(width 0.1)
				(type default)
			)
			(layer "F.Fab")
		)
		(fp_line
			(start -0.681736 0.30607)
			(end -0.681736 -0.307086)
			(stroke
				(width 0.1)
				(type default)
			)
			(layer "F.Fab")
		)
		(fp_line
			(start -0.681736 -0.307086)
			(end -0.118364 -0.307086)
			(stroke
				(width 0.1)
				(type default)
			)
			(layer "F.Fab")
		)
		(pad "1" smd rect
			(at -0.40005 0)
			(size 0.4572 0.508)
			(layers "F.Cu" "F.Mask" "F.Paste")
			(net "P1V8_CPU1_RT_1D")
		)
		(pad "2" smd rect
			(at 0.40005 0)
			(size 0.4572 0.508)
			(layers "F.Cu" "F.Mask" "F.Paste")
			(net "P1V8_CPU1_RT0_1A_1D")
		)
	)
	(footprint ""
		(layer "F.Cu")
		(at 51.498754 -370.57203 -90)
		(property "Reference" "C825"
			(at 0 0 270)
			(layer "F.SilkS")
			(hide yes)
			(effects
				(font
					(size 1.27 1.27)
				)
			)
		)
		(property "Value" ""
			(at 0 0 270)
			(layer "F.Fab")
			(effects
				(font
					(size 1.27 1.27)
				)
			)
		)
		(duplicate_pad_numbers_are_jumpers no)
		(fp_line
			(start -0.299974 0.150114)
			(end -0.299974 -0.150114)
			(stroke
				(width 0.1)
				(type default)
			)
			(layer "F.Fab")
		)
		(fp_line
			(start 0.299974 0.150114)
			(end -0.299974 0.150114)
			(stroke
				(width 0.1)
				(type default)
			)
			(layer "F.Fab")
		)
		(fp_line
			(start -0.299974 -0.150114)
			(end 0.299974 -0.150114)
			(stroke
				(width 0.1)
				(type default)
			)
			(layer "F.Fab")
		)
		(fp_line
			(start 0.299974 -0.150114)
			(end 0.299974 0.150114)
			(stroke
				(width 0.1)
				(type default)
			)
			(layer "F.Fab")
		)
		(pad "1" smd rect
			(at -0.2667 0 270)
			(size 0.3048 0.381)
			(layers "F.Cu" "F.Mask" "F.Paste")
			(net "P5E_CPU1_P0_TX_C_DP<6>")
		)
		(pad "2" smd rect
			(at 0.2667 0 270)
			(size 0.3048 0.381)
			(layers "F.Cu" "F.Mask" "F.Paste")
			(net "P5E_CPU1_P0_TX_DP<6>")
		)
	)
)
